# T6G (Grand Teton) — schematic netlist excerpt (pin names and nets, part order shuffled) for the footprints in the layout excerpt that follows; sources: Cadence DE-HDL packaged netlist, KiCad conversion of 04192023_DAF0TMB3IC0_F0TG_MB_C_brd_V02_OCP.brd

R94  Q_RES  1K 1% EMPTY  pkg 0402LF  page 91 : A = P3V3 ; B = PWRGD_CHF_CPU0_DIMM
C179  Q_CAP  10UF 25V 10% X6S  pkg C0805  page 100 : A = P12V_MEM_CPU1 ; B = GND
R550  Q_RES  4.7K 5% CHIP  pkg 0402LF  page 55 : A = CPU1_SMERR_N ; B = PVDD18_S5_P1

(kicad_pcb
	(version 20260206)
	(generator "pcbnew")
	(generator_version "10.0")
	(general
		(thickness 1.6)
		(legacy_teardrops no)
	)
	(paper "A4")
	(title_block
		(title "04192023_DAF0TMB3IC0_F0TG_MB_C_brd_V02_OCP.brd")
		(comment 1 "Grand Teton / footprints 8284-8286 of 8354")
	)
	(layers
		(0 "F.Cu" signal "TOP")
		(4 "In1.Cu" signal "GND")
		(6 "In2.Cu" signal "IN1")
		(8 "In3.Cu" signal "GND1")
		(10 "In4.Cu" signal "IN2")
		(12 "In5.Cu" signal "GND2")
		(14 "In6.Cu" signal "IN3")
		(16 "In7.Cu" signal "GND3")
		(18 "In8.Cu" signal "VCC")
		(20 "In9.Cu" signal "VCC1")
		(22 "In10.Cu" signal "GND4")
		(24 "In11.Cu" signal "IN4")
		(26 "In12.Cu" signal "GND5")
		(28 "In13.Cu" signal "IN5")
		(30 "In14.Cu" signal "GND6")
		(32 "In15.Cu" signal "IN6")
		(34 "In16.Cu" signal "GND7")
		(2 "B.Cu" signal "BOTTOM")
		(9 "F.Adhes" user "F.Adhesive")
		(11 "B.Adhes" user "B.Adhesive")
		(13 "F.Paste" user "Package Geometry/Pastemask Top")
		(15 "B.Paste" user "Package Geometry/Pastemask Bottom")
		(5 "F.SilkS" user "Ref Des/Silkscreen Top")
		(7 "B.SilkS" user "Ref Des/Silkscreen Bottom")
		(1 "F.Mask" user "Board Geometry/Soldermask Top")
		(3 "B.Mask" user "Board Geometry/Soldermask Bottom")
		(17 "Dwgs.User" user "User.Drawings")
		(19 "Cmts.User" user "User.Comments")
		(21 "Eco1.User" user "User.Eco1")
		(23 "Eco2.User" user "User.Eco2")
		(25 "Edge.Cuts" user "Board Geometry/Outline")
		(27 "Margin" user)
		(31 "F.CrtYd" user "Package Geometry/Place Bound Top")
		(29 "B.CrtYd" user "Package Geometry/Place Bound Bottom")
		(35 "F.Fab" user "Ref Des/Assembly Top")
		(33 "B.Fab" user "Ref Des/Assembly Bottom")
	)
	(footprint ""
		(layer "B.Cu")
		(at 44.340272 -192.66027)
		(property "Reference" "C179"
			(at 0 0 0)
			(layer "B.SilkS")
			(hide yes)
			(effects
				(font
					(size 1.27 1.27)
				)
				(justify mirror)
			)
		)
		(property "Value" ""
			(at 0 0 0)
			(layer "B.Fab")
			(effects
				(font
					(size 1.27 1.27)
				)
				(justify mirror)
			)
		)
		(duplicate_pad_numbers_are_jumpers no)
		(fp_line
			(start -1.524 -0.762)
			(end -1.524 0.762)
			(stroke
				(width 0.1524)
				(type default)
			)
			(layer "B.SilkS")
		)
		(fp_line
			(start -1.524 0.762)
			(end 1.524 0.762)
			(stroke
				(width 0.1524)
				(type default)
			)
			(layer "B.SilkS")
		)
		(fp_line
			(start 1.524 -0.762)
			(end -1.524 -0.762)
			(stroke
				(width 0.1524)
				(type default)
			)
			(layer "B.SilkS")
		)
		(fp_line
			(start 1.524 0.762)
			(end 1.524 -0.762)
			(stroke
				(width 0.1524)
				(type default)
			)
			(layer "B.SilkS")
		)
		(fp_line
			(start -1.1049 -0.724916)
			(end 1.1049 -0.724916)
			(stroke
				(width 0.1)
				(type default)
			)
			(layer "B.Fab")
		)
		(fp_line
			(start -1.1049 0.724916)
			(end -1.1049 -0.724916)
			(stroke
				(width 0.1)
				(type default)
			)
			(layer "B.Fab")
		)
		(fp_line
			(start 1.1049 -0.724916)
			(end 1.1049 0.724916)
			(stroke
				(width 0.1)
				(type default)
			)
			(layer "B.Fab")
		)
		(fp_line
			(start 1.1049 0.724916)
			(end -1.1049 0.724916)
			(stroke
				(width 0.1)
				(type default)
			)
			(layer "B.Fab")
		)
		(pad "1" smd rect
			(at 0.889 0)
			(size 1.016 1.27)
			(layers "B.Cu" "B.Mask" "B.Paste")
			(net "P12V_MEM_CPU1")
		)
		(pad "2" smd rect
			(at -0.889 0)
			(size 1.016 1.27)
			(layers "B.Cu" "B.Mask" "B.Paste")
			(net "GND")
		)
	)
	(footprint ""
		(layer "B.Cu")
		(at 266.30376 -193.99631)
		(property "Reference" "R94"
			(at 0 0 0)
			(layer "B.SilkS")
			(hide yes)
			(effects
				(font
					(size 1.27 1.27)
				)
				(justify mirror)
			)
		)
		(property "Value" ""
			(at 0 0 0)
			(layer "B.Fab")
			(effects
				(font
					(size 1.27 1.27)
				)
				(justify mirror)
			)
		)
		(duplicate_pad_numbers_are_jumpers no)
		(fp_line
			(start -0.7874 -0.4064)
			(end -0.7874 0.4064)
			(stroke
				(width 0.1524)
				(type default)
			)
			(layer "B.SilkS")
		)
		(fp_line
			(start -0.7874 0.4064)
			(end 0.7874 0.4064)
			(stroke
				(width 0.1524)
				(type default)
			)
			(layer "B.SilkS")
		)
		(fp_line
			(start 0.7874 -0.4064)
			(end -0.7874 -0.4064)
			(stroke
				(width 0.1524)
				(type default)
			)
			(layer "B.SilkS")
		)
		(fp_line
			(start 0.7874 0.4064)
			(end 0.7874 -0.4064)
			(stroke
				(width 0.1524)
				(type default)
			)
			(layer "B.SilkS")
		)
		(fp_line
			(start -0.67945 -0.3048)
			(end -0.67945 0.3048)
			(stroke
				(width 0.1)
				(type default)
			)
			(layer "B.Fab")
		)
		(fp_line
			(start -0.67945 0.3048)
			(end -0.120396 0.3048)
			(stroke
				(width 0.1)
				(type default)
			)
			(layer "B.Fab")
		)
		(fp_line
			(start -0.12065 -0.3048)
			(end -0.67945 -0.3048)
			(stroke
				(width 0.1)
				(type default)
			)
			(layer "B.Fab")
		)
		(fp_line
			(start -0.12065 -0.2794)
			(end -0.12065 -0.3048)
			(stroke
				(width 0.1)
				(type default)
			)
			(layer "B.Fab")
		)
		(fp_line
			(start -0.120396 0.2794)
			(end 0.12065 0.2794)
			(stroke
				(width 0.1)
				(type default)
			)
			(layer "B.Fab")
		)
		(fp_line
			(start -0.120396 0.3048)
			(end -0.120396 0.2794)
			(stroke
				(width 0.1)
				(type default)
			)
			(layer "B.Fab")
		)
		(fp_line
			(start 0.12065 -0.305054)
			(end 0.12065 -0.2794)
			(stroke
				(width 0.1)
				(type default)
			)
			(layer "B.Fab")
		)
		(fp_line
			(start 0.12065 -0.2794)
			(end -0.12065 -0.2794)
			(stroke
				(width 0.1)
				(type default)
			)
			(layer "B.Fab")
		)
		(fp_line
			(start 0.12065 0.2794)
			(end 0.12065 0.3048)
			(stroke
				(width 0.1)
				(type default)
			)
			(layer "B.Fab")
		)
		(fp_line
			(start 0.12065 0.3048)
			(end 0.67945 0.3048)
			(stroke
				(width 0.1)
				(type default)
			)
			(layer "B.Fab")
		)
		(fp_line
			(start 0.67945 -0.305054)
			(end 0.12065 -0.305054)
			(stroke
				(width 0.1)
				(type default)
			)
			(layer "B.Fab")
		)
		(fp_line
			(start 0.67945 0.3048)
			(end 0.67945 -0.305054)
			(stroke
				(width 0.1)
				(type default)
			)
			(layer "B.Fab")
		)
		(pad "1" smd circle
			(at 0.40005 0 180)
			(size 0 0)
			(layers "B.Cu" "B.Mask" "B.Paste")
			(net "P3V3")
		)
		(pad "2" smd circle
			(at -0.40005 0 180)
			(size 0 0)
			(layers "B.Cu" "B.Mask" "B.Paste")
			(net "PWRGD_CHF_CPU0_DIMM")
		)
	)
	(footprint ""
		(layer "B.Cu")
		(at 144.927574 -314.49391 180)
		(property "Reference" "R550"
			(at 0 0 0)
			(layer "B.SilkS")
			(hide yes)
			(effects
				(font
					(size 1.27 1.27)
				)
				(justify mirror)
			)
		)
		(property "Value" ""
			(at 0 0 0)
			(layer "B.Fab")
			(effects
				(font
					(size 1.27 1.27)
				)
				(justify mirror)
			)
		)
		(duplicate_pad_numbers_are_jumpers no)
		(fp_line
			(start 0.7874 0.4064)
			(end 0.7874 -0.4064)
			(stroke
				(width 0.1524)
				(type default)
			)
			(layer "B.SilkS")
		)
		(fp_line
			(start 0.7874 -0.4064)
			(end -0.7874 -0.4064)
			(stroke
				(width 0.1524)
				(type default)
			)
			(layer "B.SilkS")
		)
		(fp_line
			(start -0.7874 0.4064)
			(end 0.7874 0.4064)
			(stroke
				(width 0.1524)
				(type default)
			)
			(layer "B.SilkS")
		)
		(fp_line
			(start -0.7874 -0.4064)
			(end -0.7874 0.4064)
			(stroke
				(width 0.1524)
				(type default)
			)
			(layer "B.SilkS")
		)
		(fp_line
			(start 0.67945 0.3048)
			(end 0.67945 -0.305054)
			(stroke
				(width 0.1)
				(type default)
			)
			(layer "B.Fab")
		)
		(fp_line
			(start 0.67945 -0.305054)
			(end 0.12065 -0.305054)
			(stroke
				(width 0.1)
				(type default)
			)
			(layer "B.Fab")
		)
		(fp_line
			(start 0.12065 0.3048)
			(end 0.67945 0.3048)
			(stroke
				(width 0.1)
				(type default)
			)
			(layer "B.Fab")
		)
		(fp_line
			(start 0.12065 0.2794)
			(end 0.12065 0.3048)
			(stroke
				(width 0.1)
				(type default)
			)
			(layer "B.Fab")
		)
		(fp_line
			(start 0.12065 -0.2794)
			(end -0.12065 -0.2794)
			(stroke
				(width 0.1)
				(type default)
			)
			(layer "B.Fab")
		)
		(fp_line
			(start 0.12065 -0.305054)
			(end 0.12065 -0.2794)
			(stroke
				(width 0.1)
				(type default)
			)
			(layer "B.Fab")
		)
		(fp_line
			(start -0.120396 0.3048)
			(end -0.120396 0.2794)
			(stroke
				(width 0.1)
				(type default)
			)
			(layer "B.Fab")
		)
		(fp_line
			(start -0.120396 0.2794)
			(end 0.12065 0.2794)
			(stroke
				(width 0.1)
				(type default)
			)
			(layer "B.Fab")
		)
		(fp_line
			(start -0.12065 -0.2794)
			(end -0.12065 -0.3048)
			(stroke
				(width 0.1)
				(type default)
			)
			(layer "B.Fab")
		)
		(fp_line
			(start -0.12065 -0.3048)
			(end -0.67945 -0.3048)
			(stroke
				(width 0.1)
				(type default)
			)
			(layer "B.Fab")
		)
		(fp_line
			(start -0.67945 0.3048)
			(end -0.120396 0.3048)
			(stroke
				(width 0.1)
				(type default)
			)
			(layer "B.Fab")
		)
		(fp_line
			(start -0.67945 -0.3048)
			(end -0.67945 0.3048)
			(stroke
				(width 0.1)
				(type default)
			)
			(layer "B.Fab")
		)
		(pad "1" smd circle
			(at 0.40005 0)
			(size 0 0)
			(layers "B.Cu" "B.Mask" "B.Paste")
			(net "CPU1_SMERR_N")
		)
		(pad "2" smd circle
			(at -0.40005 0)
			(size 0 0)
			(layers "B.Cu" "B.Mask" "B.Paste")
			(net "PVDD18_S5_P1")
		)
	)
)
